(kicad_pcb
	(version 20260206)
	(generator "pcbnew")
	(generator_version "10.0")
	(general
		(thickness 1.6)
		(legacy_teardrops no)
	)
	(paper "A4")
	(title_block
		(title "04192023_DAF0TMB3IC0_F0TG_MB_C_brd_V02_OCP.brd")
		(comment 1 "Grand Teton / footprints 5437-5443 of 8354")
	)
	(layers
		(0 "F.Cu" signal "TOP")
		(4 "In1.Cu" signal "GND")
		(6 "In2.Cu" signal "IN1")
		(8 "In3.Cu" signal "GND1")
		(10 "In4.Cu" signal "IN2")
		(12 "In5.Cu" signal "GND2")
		(14 "In6.Cu" signal "IN3")
		(16 "In7.Cu" signal "GND3")
		(18 "In8.Cu" signal "VCC")
		(20 "In9.Cu" signal "VCC1")
		(22 "In10.Cu" signal "GND4")
		(24 "In11.Cu" signal "IN4")
		(26 "In12.Cu" signal "GND5")
		(28 "In13.Cu" signal "IN5")
		(30 "In14.Cu" signal "GND6")
		(32 "In15.Cu" signal "IN6")
		(34 "In16.Cu" signal "GND7")
		(2 "B.Cu" signal "BOTTOM")
		(9 "F.Adhes" user "F.Adhesive")
		(11 "B.Adhes" user "B.Adhesive")
		(13 "F.Paste" user "Package Geometry/Pastemask Top")
		(15 "B.Paste" user "Package Geometry/Pastemask Bottom")
		(5 "F.SilkS" user "Ref Des/Silkscreen Top")
		(7 "B.SilkS" user "Ref Des/Silkscreen Bottom")
		(1 "F.Mask" user "Board Geometry/Soldermask Top")
		(3 "B.Mask" user "Board Geometry/Soldermask Bottom")
		(17 "Dwgs.User" user "User.Drawings")
		(19 "Cmts.User" user "User.Comments")
		(21 "Eco1.User" user "User.Eco1")
		(23 "Eco2.User" user "User.Eco2")
		(25 "Edge.Cuts" user "Board Geometry/Outline")
		(27 "Margin" user)
		(31 "F.CrtYd" user "Package Geometry/Place Bound Top")
		(29 "B.CrtYd" user "Package Geometry/Place Bound Bottom")
		(35 "F.Fab" user "Ref Des/Assembly Top")
		(33 "B.Fab" user "Ref Des/Assembly Bottom")
	)
	(footprint ""
		(layer "B.Cu")
		(at 350.818958 -249.36831 180)
		(property "Reference" "C1922"
			(at 0 0 0)
			(layer "B.SilkS")
			(hide yes)
			(effects
				(font
					(size 1.27 1.27)
				)
				(justify mirror)
			)
		)
		(property "Value" ""
			(at 0 0 0)
			(layer "B.Fab")
			(effects
				(font
					(size 1.27 1.27)
				)
				(justify mirror)
			)
		)
		(duplicate_pad_numbers_are_jumpers no)
		(fp_line
			(start 0.7874 0.4064)
			(end 0.7874 -0.4064)
			(stroke
				(width 0.1524)
				(type default)
			)
			(layer "B.SilkS")
		)
		(fp_line
			(start 0.7874 -0.4064)
			(end -0.7874 -0.4064)
			(stroke
				(width 0.1524)
				(type default)
			)
			(layer "B.SilkS")
		)
		(fp_line
			(start -0.7874 0.4064)
			(end 0.7874 0.4064)
			(stroke
				(width 0.1524)
				(type default)
			)
			(layer "B.SilkS")
		)
		(fp_line
			(start -0.7874 -0.4064)
			(end -0.7874 0.4064)
			(stroke
				(width 0.1524)
				(type default)
			)
			(layer "B.SilkS")
		)
		(fp_line
			(start 0.67945 0.3048)
			(end 0.67945 -0.305054)
			(stroke
				(width 0.1)
				(type default)
			)
			(layer "B.Fab")
		)
		(fp_line
			(start 0.67945 -0.305054)
			(end 0.12065 -0.305054)
			(stroke
				(width 0.1)
				(type default)
			)
			(layer "B.Fab")
		)
		(fp_line
			(start 0.12065 0.3048)
			(end 0.67945 0.3048)
			(stroke
				(width 0.1)
				(type default)
			)
			(layer "B.Fab")
		)
		(fp_line
			(start 0.12065 0.2794)
			(end 0.12065 0.3048)
			(stroke
				(width 0.1)
				(type default)
			)
			(layer "B.Fab")
		)
		(fp_line
			(start 0.12065 -0.2794)
			(end -0.12065 -0.2794)
			(stroke
				(width 0.1)
				(type default)
			)
			(layer "B.Fab")
		)
		(fp_line
			(start 0.12065 -0.305054)
			(end 0.12065 -0.2794)
			(stroke
				(width 0.1)
				(type default)
			)
			(layer "B.Fab")
		)
		(fp_line
			(start -0.120396 0.3048)
			(end -0.120396 0.2794)
			(stroke
				(width 0.1)
				(type default)
			)
			(layer "B.Fab")
		)
		(fp_line
			(start -0.120396 0.2794)
			(end 0.12065 0.2794)
			(stroke
				(width 0.1)
				(type default)
			)
			(layer "B.Fab")
		)
		(fp_line
			(start -0.12065 -0.2794)
			(end -0.12065 -0.3048)
			(stroke
				(width 0.1)
				(type default)
			)
			(layer "B.Fab")
		)
		(fp_line
			(start -0.12065 -0.3048)
			(end -0.67945 -0.3048)
			(stroke
				(width 0.1)
				(type default)
			)
			(layer "B.Fab")
		)
		(fp_line
			(start -0.67945 0.3048)
			(end -0.120396 0.3048)
			(stroke
				(width 0.1)
				(type default)
			)
			(layer "B.Fab")
		)
		(fp_line
			(start -0.67945 -0.3048)
			(end -0.67945 0.3048)
			(stroke
				(width 0.1)
				(type default)
			)
			(layer "B.Fab")
		)
		(pad "1" smd circle
			(at 0.40005 0)
			(size 0 0)
			(layers "B.Cu" "B.Mask" "B.Paste")
			(net "PVDDCR_CPU0_P0")
		)
		(pad "2" smd circle
			(at -0.40005 0)
			(size 0 0)
			(layers "B.Cu" "B.Mask" "B.Paste")
			(net "GND")
		)
	)
	(footprint ""
		(layer "B.Cu")
		(at 122.878596 -386.766562 90)
		(property "Reference" "C443"
			(at 0 0 90)
			(layer "B.SilkS")
			(hide yes)
			(effects
				(font
					(size 1.27 1.27)
				)
				(justify mirror)
			)
		)
		(property "Value" ""
			(at 0 0 90)
			(layer "B.Fab")
			(effects
				(font
					(size 1.27 1.27)
				)
				(justify mirror)
			)
		)
		(duplicate_pad_numbers_are_jumpers no)
		(fp_line
			(start 0.299974 -0.150114)
			(end -0.299974 -0.150114)
			(stroke
				(width 0.1)
				(type default)
			)
			(layer "B.Fab")
		)
		(fp_line
			(start -0.299974 -0.150114)
			(end -0.299974 0.150114)
			(stroke
				(width 0.1)
				(type default)
			)
			(layer "B.Fab")
		)
		(fp_line
			(start 0.299974 0.150114)
			(end 0.299974 -0.150114)
			(stroke
				(width 0.1)
				(type default)
			)
			(layer "B.Fab")
		)
		(fp_line
			(start -0.299974 0.150114)
			(end 0.299974 0.150114)
			(stroke
				(width 0.1)
				(type default)
			)
			(layer "B.Fab")
		)
		(pad "1" smd rect
			(at 0.2667 0 270)
			(size 0.3048 0.381)
			(layers "B.Cu" "B.Mask" "B.Paste")
			(net "P1V8_CPU1_RT3_1A")
		)
		(pad "2" smd rect
			(at -0.2667 0 270)
			(size 0.3048 0.381)
			(layers "B.Cu" "B.Mask" "B.Paste")
			(net "GND")
		)
	)
	(footprint ""
		(layer "B.Cu")
		(at 182.332376 -115.022376 180)
		(property "Reference" "C355"
			(at 0 0 0)
			(layer "B.SilkS")
			(hide yes)
			(effects
				(font
					(size 1.27 1.27)
				)
				(justify mirror)
			)
		)
		(property "Value" ""
			(at 0 0 0)
			(layer "B.Fab")
			(effects
				(font
					(size 1.27 1.27)
				)
				(justify mirror)
			)
		)
		(duplicate_pad_numbers_are_jumpers no)
		(fp_line
			(start 0.69215 0.2921)
			(end 0.69215 -0.2921)
			(stroke
				(width 0.1524)
				(type default)
			)
			(layer "B.SilkS")
		)
		(fp_line
			(start 0.69215 -0.2921)
			(end -0.69215 -0.2921)
			(stroke
				(width 0.1524)
				(type default)
			)
			(layer "B.SilkS")
		)
		(fp_line
			(start -0.69215 0.2921)
			(end 0.69215 0.2921)
			(stroke
				(width 0.1524)
				(type default)
			)
			(layer "B.SilkS")
		)
		(fp_line
			(start -0.69215 -0.2921)
			(end -0.69215 0.2921)
			(stroke
				(width 0.1524)
				(type default)
			)
			(layer "B.SilkS")
		)
		(fp_line
			(start 0.51435 0.2794)
			(end 0.51435 -0.2794)
			(stroke
				(width 0.1)
				(type default)
			)
			(layer "B.Fab")
		)
		(fp_line
			(start 0.51435 -0.2794)
			(end -0.51435 -0.2794)
			(stroke
				(width 0.1)
				(type default)
			)
			(layer "B.Fab")
		)
		(fp_line
			(start -0.51435 0.2794)
			(end 0.51435 0.2794)
			(stroke
				(width 0.1)
				(type default)
			)
			(layer "B.Fab")
		)
		(fp_line
			(start -0.51435 -0.2794)
			(end -0.51435 0.2794)
			(stroke
				(width 0.1)
				(type default)
			)
			(layer "B.Fab")
		)
		(pad "1" smd circle
			(at 0.40005 0)
			(size 0 0)
			(layers "B.Cu" "B.Mask" "B.Paste")
			(net "P3V3_AUX")
		)
		(pad "2" smd circle
			(at -0.40005 0)
			(size 0 0)
			(layers "B.Cu" "B.Mask" "B.Paste")
			(net "GND")
		)
		(zone
			(layer "B.Cu")
			(hatch none 0.5)
			(connect_pads
				(clearance 0)
			)
			(min_thickness 0.25)
			(keepout
				(tracks not_allowed)
				(vias allowed)
				(pads allowed)
				(copperpour not_allowed)
				(footprints allowed)
			)
			(placement
				(enabled no)
				(sheetname "")
			)
			(fill
				(thermal_gap 0.5)
				(thermal_bridge_width 0.5)
				(island_removal_mode 0)
			)
			(polygon
				(pts
					(xy 182.141876 -114.934492) (xy 182.141876 -115.110006) (xy 182.233316 -115.168172) (xy 182.432706 -115.168172)
					(xy 182.522876 -115.110006) (xy 182.522876 -114.934746) (xy 182.432706 -114.876326) (xy 182.233316 -114.876326)
				)
			)
		)
	)
	(footprint ""
		(layer "B.Cu")
		(at 419.684454 -191.32931 180)
		(property "Reference" "R298"
			(at 0 0 0)
			(layer "B.SilkS")
			(hide yes)
			(effects
				(font
					(size 1.27 1.27)
				)
				(justify mirror)
			)
		)
		(property "Value" ""
			(at 0 0 0)
			(layer "B.Fab")
			(effects
				(font
					(size 1.27 1.27)
				)
				(justify mirror)
			)
		)
		(duplicate_pad_numbers_are_jumpers no)
		(fp_line
			(start 0.7874 0.4064)
			(end 0.7874 -0.4064)
			(stroke
				(width 0.1524)
				(type default)
			)
			(layer "B.SilkS")
		)
		(fp_line
			(start 0.7874 -0.4064)
			(end -0.7874 -0.4064)
			(stroke
				(width 0.1524)
				(type default)
			)
			(layer "B.SilkS")
		)
		(fp_line
			(start -0.7874 0.4064)
			(end 0.7874 0.4064)
			(stroke
				(width 0.1524)
				(type default)
			)
			(layer "B.SilkS")
		)
		(fp_line
			(start -0.7874 -0.4064)
			(end -0.7874 0.4064)
			(stroke
				(width 0.1524)
				(type default)
			)
			(layer "B.SilkS")
		)
		(fp_line
			(start 0.67945 0.3048)
			(end 0.67945 -0.305054)
			(stroke
				(width 0.1)
				(type default)
			)
			(layer "B.Fab")
		)
		(fp_line
			(start 0.67945 -0.305054)
			(end 0.12065 -0.305054)
			(stroke
				(width 0.1)
				(type default)
			)
			(layer "B.Fab")
		)
		(fp_line
			(start 0.12065 0.3048)
			(end 0.67945 0.3048)
			(stroke
				(width 0.1)
				(type default)
			)
			(layer "B.Fab")
		)
		(fp_line
			(start 0.12065 0.2794)
			(end 0.12065 0.3048)
			(stroke
				(width 0.1)
				(type default)
			)
			(layer "B.Fab")
		)
		(fp_line
			(start 0.12065 -0.2794)
			(end -0.12065 -0.2794)
			(stroke
				(width 0.1)
				(type default)
			)
			(layer "B.Fab")
		)
		(fp_line
			(start 0.12065 -0.305054)
			(end 0.12065 -0.2794)
			(stroke
				(width 0.1)
				(type default)
			)
			(layer "B.Fab")
		)
		(fp_line
			(start -0.120396 0.3048)
			(end -0.120396 0.2794)
			(stroke
				(width 0.1)
				(type default)
			)
			(layer "B.Fab")
		)
		(fp_line
			(start -0.120396 0.2794)
			(end 0.12065 0.2794)
			(stroke
				(width 0.1)
				(type default)
			)
			(layer "B.Fab")
		)
		(fp_line
			(start -0.12065 -0.2794)
			(end -0.12065 -0.3048)
			(stroke
				(width 0.1)
				(type default)
			)
			(layer "B.Fab")
		)
		(fp_line
			(start -0.12065 -0.3048)
			(end -0.67945 -0.3048)
			(stroke
				(width 0.1)
				(type default)
			)
			(layer "B.Fab")
		)
		(fp_line
			(start -0.67945 0.3048)
			(end -0.120396 0.3048)
			(stroke
				(width 0.1)
				(type default)
			)
			(layer "B.Fab")
		)
		(fp_line
			(start -0.67945 -0.3048)
			(end -0.67945 0.3048)
			(stroke
				(width 0.1)
				(type default)
			)
			(layer "B.Fab")
		)
		(pad "1" smd circle
			(at 0.40005 0)
			(size 0 0)
			(layers "B.Cu" "B.Mask" "B.Paste")
			(net "PWRGD_CHH_CPU0_DIMM")
		)
		(pad "2" smd circle
			(at -0.40005 0)
			(size 0 0)
			(layers "B.Cu" "B.Mask" "B.Paste")
			(net "PWRGD_CHGL_CPU0")
		)
	)
	(footprint ""
		(layer "B.Cu")
		(at 285.23311 -416.255962 -90)
		(property "Reference" "C81"
			(at 0 0 90)
			(layer "B.SilkS")
			(hide yes)
			(effects
				(font
					(size 1.27 1.27)
				)
				(justify mirror)
			)
		)
		(property "Value" ""
			(at 0 0 90)
			(layer "B.Fab")
			(effects
				(font
					(size 1.27 1.27)
				)
				(justify mirror)
			)
		)
		(duplicate_pad_numbers_are_jumpers no)
		(fp_line
			(start -0.7874 0.4064)
			(end 0.7874 0.4064)
			(stroke
				(width 0.1524)
				(type default)
			)
			(layer "B.SilkS")
		)
		(fp_line
			(start 0.7874 0.4064)
			(end 0.7874 -0.4064)
			(stroke
				(width 0.1524)
				(type default)
			)
			(layer "B.SilkS")
		)
		(fp_line
			(start -0.7874 -0.4064)
			(end -0.7874 0.4064)
			(stroke
				(width 0.1524)
				(type default)
			)
			(layer "B.SilkS")
		)
		(fp_line
			(start 0.7874 -0.4064)
			(end -0.7874 -0.4064)
			(stroke
				(width 0.1524)
				(type default)
			)
			(layer "B.SilkS")
		)
		(fp_line
			(start -0.67945 0.3048)
			(end -0.120396 0.3048)
			(stroke
				(width 0.1)
				(type default)
			)
			(layer "B.Fab")
		)
		(fp_line
			(start -0.120396 0.3048)
			(end -0.120396 0.2794)
			(stroke
				(width 0.1)
				(type default)
			)
			(layer "B.Fab")
		)
		(fp_line
			(start 0.12065 0.3048)
			(end 0.67945 0.3048)
			(stroke
				(width 0.1)
				(type default)
			)
			(layer "B.Fab")
		)
		(fp_line
			(start 0.67945 0.3048)
			(end 0.67945 -0.305054)
			(stroke
				(width 0.1)
				(type default)
			)
			(layer "B.Fab")
		)
		(fp_line
			(start -0.120396 0.2794)
			(end 0.12065 0.2794)
			(stroke
				(width 0.1)
				(type default)
			)
			(layer "B.Fab")
		)
		(fp_line
			(start 0.12065 0.2794)
			(end 0.12065 0.3048)
			(stroke
				(width 0.1)
				(type default)
			)
			(layer "B.Fab")
		)
		(fp_line
			(start -0.12065 -0.2794)
			(end -0.12065 -0.3048)
			(stroke
				(width 0.1)
				(type default)
			)
			(layer "B.Fab")
		)
		(fp_line
			(start 0.12065 -0.2794)
			(end -0.12065 -0.2794)
			(stroke
				(width 0.1)
				(type default)
			)
			(layer "B.Fab")
		)
		(fp_line
			(start -0.67945 -0.3048)
			(end -0.67945 0.3048)
			(stroke
				(width 0.1)
				(type default)
			)
			(layer "B.Fab")
		)
		(fp_line
			(start -0.12065 -0.3048)
			(end -0.67945 -0.3048)
			(stroke
				(width 0.1)
				(type default)
			)
			(layer "B.Fab")
		)
		(fp_line
			(start 0.12065 -0.305054)
			(end 0.12065 -0.2794)
			(stroke
				(width 0.1)
				(type default)
			)
			(layer "B.Fab")
		)
		(fp_line
			(start 0.67945 -0.305054)
			(end 0.12065 -0.305054)
			(stroke
				(width 0.1)
				(type default)
			)
			(layer "B.Fab")
		)
		(pad "1" smd circle
			(at 0.40005 0 90)
			(size 0 0)
			(layers "B.Cu" "B.Mask" "B.Paste")
			(net "P3V3_9ZXL045_P0_VDD")
		)
		(pad "2" smd circle
			(at -0.40005 0 90)
			(size 0 0)
			(layers "B.Cu" "B.Mask" "B.Paste")
			(net "GND")
		)
	)
	(footprint ""
		(layer "B.Cu")
		(at 364.407958 -245.487952)
		(property "Reference" "C267"
			(at 0 0 0)
			(layer "B.SilkS")
			(hide yes)
			(effects
				(font
					(size 1.27 1.27)
				)
				(justify mirror)
			)
		)
		(property "Value" ""
			(at 0 0 0)
			(layer "B.Fab")
			(effects
				(font
					(size 1.27 1.27)
				)
				(justify mirror)
			)
		)
		(duplicate_pad_numbers_are_jumpers no)
		(fp_line
			(start -0.7874 -0.4064)
			(end -0.7874 0.4064)
			(stroke
				(width 0.1524)
				(type default)
			)
			(layer "B.SilkS")
		)
		(fp_line
			(start -0.7874 0.4064)
			(end 0.7874 0.4064)
			(stroke
				(width 0.1524)
				(type default)
			)
			(layer "B.SilkS")
		)
		(fp_line
			(start 0.7874 -0.4064)
			(end -0.7874 -0.4064)
			(stroke
				(width 0.1524)
				(type default)
			)
			(layer "B.SilkS")
		)
		(fp_line
			(start 0.7874 0.4064)
			(end 0.7874 -0.4064)
			(stroke
				(width 0.1524)
				(type default)
			)
			(layer "B.SilkS")
		)
		(fp_line
			(start -0.67945 -0.3048)
			(end -0.67945 0.3048)
			(stroke
				(width 0.1)
				(type default)
			)
			(layer "B.Fab")
		)
		(fp_line
			(start -0.67945 0.3048)
			(end -0.120396 0.3048)
			(stroke
				(width 0.1)
				(type default)
			)
			(layer "B.Fab")
		)
		(fp_line
			(start -0.12065 -0.3048)
			(end -0.67945 -0.3048)
			(stroke
				(width 0.1)
				(type default)
			)
			(layer "B.Fab")
		)
		(fp_line
			(start -0.12065 -0.2794)
			(end -0.12065 -0.3048)
			(stroke
				(width 0.1)
				(type default)
			)
			(layer "B.Fab")
		)
		(fp_line
			(start -0.120396 0.2794)
			(end 0.12065 0.2794)
			(stroke
				(width 0.1)
				(type default)
			)
			(layer "B.Fab")
		)
		(fp_line
			(start -0.120396 0.3048)
			(end -0.120396 0.2794)
			(stroke
				(width 0.1)
				(type default)
			)
			(layer "B.Fab")
		)
		(fp_line
			(start 0.12065 -0.305054)
			(end 0.12065 -0.2794)
			(stroke
				(width 0.1)
				(type default)
			)
			(layer "B.Fab")
		)
		(fp_line
			(start 0.12065 -0.2794)
			(end -0.12065 -0.2794)
			(stroke
				(width 0.1)
				(type default)
			)
			(layer "B.Fab")
		)
		(fp_line
			(start 0.12065 0.2794)
			(end 0.12065 0.3048)
			(stroke
				(width 0.1)
				(type default)
			)
			(layer "B.Fab")
		)
		(fp_line
			(start 0.12065 0.3048)
			(end 0.67945 0.3048)
			(stroke
				(width 0.1)
				(type default)
			)
			(layer "B.Fab")
		)
		(fp_line
			(start 0.67945 -0.305054)
			(end 0.12065 -0.305054)
			(stroke
				(width 0.1)
				(type default)
			)
			(layer "B.Fab")
		)
		(fp_line
			(start 0.67945 0.3048)
			(end 0.67945 -0.305054)
			(stroke
				(width 0.1)
				(type default)
			)
			(layer "B.Fab")
		)
		(pad "1" smd circle
			(at 0.40005 0 180)
			(size 0 0)
			(layers "B.Cu" "B.Mask" "B.Paste")
			(net "PVDDCR_CPU0_P0")
		)
		(pad "2" smd circle
			(at -0.40005 0 180)
			(size 0 0)
			(layers "B.Cu" "B.Mask" "B.Paste")
			(net "GND")
		)
	)
	(footprint ""
		(layer "B.Cu")
		(at 64.889126 -20.04822)
		(property "Reference" "PC2141"
			(at 0 0 0)
			(layer "B.SilkS")
			(hide yes)
			(effects
				(font
					(size 1.27 1.27)
				)
				(justify mirror)
			)
		)
		(property "Value" ""
			(at 0 0 0)
			(layer "B.Fab")
			(effects
				(font
					(size 1.27 1.27)
				)
				(justify mirror)
			)
		)
		(duplicate_pad_numbers_are_jumpers no)
		(fp_line
			(start -1.524 -0.762)
			(end -1.524 0.762)
			(stroke
				(width 0.1524)
				(type default)
			)
			(layer "B.SilkS")
		)
		(fp_line
			(start -1.524 0.762)
			(end 1.524 0.762)
			(stroke
				(width 0.1524)
				(type default)
			)
			(layer "B.SilkS")
		)
		(fp_line
			(start 1.524 -0.762)
			(end -1.524 -0.762)
			(stroke
				(width 0.1524)
				(type default)
			)
			(layer "B.SilkS")
		)
		(fp_line
			(start 1.524 0.762)
			(end 1.524 -0.762)
			(stroke
				(width 0.1524)
				(type default)
			)
			(layer "B.SilkS")
		)
		(fp_line
			(start -1.1049 -0.724916)
			(end 1.1049 -0.724916)
			(stroke
				(width 0.1)
				(type default)
			)
			(layer "B.Fab")
		)
		(fp_line
			(start -1.1049 0.724916)
			(end -1.1049 -0.724916)
			(stroke
				(width 0.1)
				(type default)
			)
			(layer "B.Fab")
		)
		(fp_line
			(start 1.1049 -0.724916)
			(end 1.1049 0.724916)
			(stroke
				(width 0.1)
				(type default)
			)
			(layer "B.Fab")
		)
		(fp_line
			(start 1.1049 0.724916)
			(end -1.1049 0.724916)
			(stroke
				(width 0.1)
				(type default)
			)
			(layer "B.Fab")
		)
		(pad "1" smd rect
			(at 0.889 0)
			(size 1.016 1.27)
			(layers "B.Cu" "B.Mask" "B.Paste")
			(net "P12V_OCP_V3_2")
		)
		(pad "2" smd rect
			(at -0.889 0)
			(size 1.016 1.27)
			(layers "B.Cu" "B.Mask" "B.Paste")
			(net "GND")
		)
	)
)
